# S9S_MB_2U (Grand Teton) — schematic netlist excerpt (pin names and nets, part order shuffled) for the footprints in the layout excerpt that follows; sources: Cadence DE-HDL packaged netlist, KiCad conversion of 03242023_DA0F0TMBIJ0_F0T_Motherboard_J_brd_V01_OCP.brd

PR2536  Q_RES  10 1% EMPTY  pkg 0402LF  page 304 : A = P12V_HSC_GATE_G6 ; B = P12V_HSC_GATE2
C581  Q_CAP  0.1UF 25V 10% X7R  pkg 0402  page 158 : A = P3V3_AUX ; B = GND

(kicad_pcb
	(version 20260206)
	(generator "pcbnew")
	(generator_version "10.0")
	(general
		(thickness 1.6)
		(legacy_teardrops no)
	)
	(paper "A4")
	(title_block
		(title "03242023_DA0F0TMBIJ0_F0T_Motherboard_J_brd_V01_OCP.brd")
		(comment 1 "Grand Teton / footprints 2229-2230 of 6105")
	)
	(layers
		(0 "F.Cu" signal "TOP")
		(4 "In1.Cu" signal "GND")
		(6 "In2.Cu" signal "IN1")
		(8 "In3.Cu" signal "GND1")
		(10 "In4.Cu" signal "IN2")
		(12 "In5.Cu" signal "GND2")
		(14 "In6.Cu" signal "IN3")
		(16 "In7.Cu" signal "GND3")
		(18 "In8.Cu" signal "VCC")
		(20 "In9.Cu" signal "VCC1")
		(22 "In10.Cu" signal "GND4")
		(24 "In11.Cu" signal "IN4")
		(26 "In12.Cu" signal "GND5")
		(28 "In13.Cu" signal "IN5")
		(30 "In14.Cu" signal "GND6")
		(32 "In15.Cu" signal "IN6")
		(34 "In16.Cu" signal "GND7")
		(2 "B.Cu" signal "BOTTOM")
		(9 "F.Adhes" user "F.Adhesive")
		(11 "B.Adhes" user "B.Adhesive")
		(13 "F.Paste" user "Package Geometry/Pastemask Top")
		(15 "B.Paste" user "Package Geometry/Pastemask Bottom")
		(5 "F.SilkS" user "Ref Des/Silkscreen Top")
		(7 "B.SilkS" user "Ref Des/Silkscreen Bottom")
		(1 "F.Mask" user "Board Geometry/Soldermask Top")
		(3 "B.Mask" user "Board Geometry/Soldermask Bottom")
		(17 "Dwgs.User" user "User.Drawings")
		(19 "Cmts.User" user "User.Comments")
		(21 "Eco1.User" user "User.Eco1")
		(23 "Eco2.User" user "User.Eco2")
		(25 "Edge.Cuts" user "Board Geometry/Outline")
		(27 "Margin" user)
		(31 "F.CrtYd" user "Package Geometry/Place Bound Top")
		(29 "B.CrtYd" user "Package Geometry/Place Bound Bottom")
		(35 "F.Fab" user "Ref Des/Assembly Top")
		(33 "B.Fab" user "Ref Des/Assembly Bottom")
	)
	(footprint ""
		(layer "F.Cu")
		(at 392.163808 -38.829742)
		(property "Reference" "C581"
			(at 0 0 0)
			(layer "F.SilkS")
			(hide yes)
			(effects
				(font
					(size 1.27 1.27)
				)
			)
		)
		(property "Value" ""
			(at 0 0 0)
			(layer "F.Fab")
			(effects
				(font
					(size 1.27 1.27)
				)
			)
		)
		(duplicate_pad_numbers_are_jumpers no)
		(fp_line
			(start -0.7874 -0.4064)
			(end 0.7874 -0.4064)
			(stroke
				(width 0.1524)
				(type default)
			)
			(layer "F.SilkS")
		)
		(fp_line
			(start -0.7874 0.4064)
			(end -0.7874 -0.4064)
			(stroke
				(width 0.1524)
				(type default)
			)
			(layer "F.SilkS")
		)
		(fp_line
			(start 0.7874 -0.4064)
			(end 0.7874 0.4064)
			(stroke
				(width 0.1524)
				(type default)
			)
			(layer "F.SilkS")
		)
		(fp_line
			(start 0.7874 0.4064)
			(end -0.7874 0.4064)
			(stroke
				(width 0.1524)
				(type default)
			)
			(layer "F.SilkS")
		)
		(fp_line
			(start -0.67945 -0.305054)
			(end -0.12065 -0.305054)
			(stroke
				(width 0.1)
				(type default)
			)
			(layer "F.Fab")
		)
		(fp_line
			(start -0.67945 0.3048)
			(end -0.67945 -0.305054)
			(stroke
				(width 0.1)
				(type default)
			)
			(layer "F.Fab")
		)
		(fp_line
			(start -0.12065 -0.305054)
			(end -0.12065 -0.2794)
			(stroke
				(width 0.1)
				(type default)
			)
			(layer "F.Fab")
		)
		(fp_line
			(start -0.12065 -0.2794)
			(end 0.12065 -0.2794)
			(stroke
				(width 0.1)
				(type default)
			)
			(layer "F.Fab")
		)
		(fp_line
			(start -0.12065 0.2794)
			(end -0.12065 0.3048)
			(stroke
				(width 0.1)
				(type default)
			)
			(layer "F.Fab")
		)
		(fp_line
			(start -0.12065 0.3048)
			(end -0.67945 0.3048)
			(stroke
				(width 0.1)
				(type default)
			)
			(layer "F.Fab")
		)
		(fp_line
			(start 0.120396 0.2794)
			(end -0.12065 0.2794)
			(stroke
				(width 0.1)
				(type default)
			)
			(layer "F.Fab")
		)
		(fp_line
			(start 0.120396 0.3048)
			(end 0.120396 0.2794)
			(stroke
				(width 0.1)
				(type default)
			)
			(layer "F.Fab")
		)
		(fp_line
			(start 0.12065 -0.3048)
			(end 0.67945 -0.3048)
			(stroke
				(width 0.1)
				(type default)
			)
			(layer "F.Fab")
		)
		(fp_line
			(start 0.12065 -0.2794)
			(end 0.12065 -0.3048)
			(stroke
				(width 0.1)
				(type default)
			)
			(layer "F.Fab")
		)
		(fp_line
			(start 0.67945 -0.3048)
			(end 0.67945 0.3048)
			(stroke
				(width 0.1)
				(type default)
			)
			(layer "F.Fab")
		)
		(fp_line
			(start 0.67945 0.3048)
			(end 0.120396 0.3048)
			(stroke
				(width 0.1)
				(type default)
			)
			(layer "F.Fab")
		)
		(pad "1" smd circle
			(at -0.40005 0)
			(size 0 0)
			(layers "F.Cu" "F.Mask" "F.Paste")
			(net "P3V3_AUX")
		)
		(pad "2" smd circle
			(at 0.40005 0)
			(size 0 0)
			(layers "F.Cu" "F.Mask" "F.Paste")
			(net "GND")
		)
	)
	(footprint ""
		(layer "F.Cu")
		(at 250.53163 -394.17117)
		(property "Reference" "PR2536"
			(at 0 0 0)
			(layer "F.SilkS")
			(hide yes)
			(effects
				(font
					(size 1.27 1.27)
				)
			)
		)
		(property "Value" ""
			(at 0 0 0)
			(layer "F.Fab")
			(effects
				(font
					(size 1.27 1.27)
				)
			)
		)
		(duplicate_pad_numbers_are_jumpers no)
		(fp_line
			(start -0.7874 -0.4064)
			(end 0.7874 -0.4064)
			(stroke
				(width 0.1524)
				(type default)
			)
			(layer "F.SilkS")
		)
		(fp_line
			(start -0.7874 0.4064)
			(end -0.7874 -0.4064)
			(stroke
				(width 0.1524)
				(type default)
			)
			(layer "F.SilkS")
		)
		(fp_line
			(start 0.7874 -0.4064)
			(end 0.7874 0.4064)
			(stroke
				(width 0.1524)
				(type default)
			)
			(layer "F.SilkS")
		)
		(fp_line
			(start 0.7874 0.4064)
			(end -0.7874 0.4064)
			(stroke
				(width 0.1524)
				(type default)
			)
			(layer "F.SilkS")
		)
		(fp_line
			(start -0.67945 -0.305054)
			(end -0.12065 -0.305054)
			(stroke
				(width 0.1)
				(type default)
			)
			(layer "F.Fab")
		)
		(fp_line
			(start -0.67945 0.3048)
			(end -0.67945 -0.305054)
			(stroke
				(width 0.1)
				(type default)
			)
			(layer "F.Fab")
		)
		(fp_line
			(start -0.12065 -0.305054)
			(end -0.12065 -0.2794)
			(stroke
				(width 0.1)
				(type default)
			)
			(layer "F.Fab")
		)
		(fp_line
			(start -0.12065 -0.2794)
			(end 0.12065 -0.2794)
			(stroke
				(width 0.1)
				(type default)
			)
			(layer "F.Fab")
		)
		(fp_line
			(start -0.12065 0.2794)
			(end -0.12065 0.3048)
			(stroke
				(width 0.1)
				(type default)
			)
			(layer "F.Fab")
		)
		(fp_line
			(start -0.12065 0.3048)
			(end -0.67945 0.3048)
			(stroke
				(width 0.1)
				(type default)
			)
			(layer "F.Fab")
		)
		(fp_line
			(start 0.120396 0.2794)
			(end -0.12065 0.2794)
			(stroke
				(width 0.1)
				(type default)
			)
			(layer "F.Fab")
		)
		(fp_line
			(start 0.120396 0.3048)
			(end 0.120396 0.2794)
			(stroke
				(width 0.1)
				(type default)
			)
			(layer "F.Fab")
		)
		(fp_line
			(start 0.12065 -0.3048)
			(end 0.67945 -0.3048)
			(stroke
				(width 0.1)
				(type default)
			)
			(layer "F.Fab")
		)
		(fp_line
			(start 0.12065 -0.2794)
			(end 0.12065 -0.3048)
			(stroke
				(width 0.1)
				(type default)
			)
			(layer "F.Fab")
		)
		(fp_line
			(start 0.67945 -0.3048)
			(end 0.67945 0.3048)
			(stroke
				(width 0.1)
				(type default)
			)
			(layer "F.Fab")
		)
		(fp_line
			(start 0.67945 0.3048)
			(end 0.120396 0.3048)
			(stroke
				(width 0.1)
				(type default)
			)
			(layer "F.Fab")
		)
		(pad "1" smd circle
			(at -0.40005 0)
			(size 0 0)
			(layers "F.Cu" "F.Mask" "F.Paste")
			(net "P12V_HSC_GATE_G6")
		)
		(pad "2" smd circle
			(at 0.40005 0)
			(size 0 0)
			(layers "F.Cu" "F.Mask" "F.Paste")
			(net "P12V_HSC_GATE2")
		)
	)
)
